;LEADER: 12 
;HEADER: 
;CODE  : ASCII 
;FILE  : 9127_F0T_Expander_BD_F_v02_0110_1240-bd-1-13.drl for backdrilling ... from layer TOP to layer GND5
;DESIGN: 9127_F0T_Expander_BD_F_v02_0110_1240.brd
;MUST-NOT-CUT-LAYER = IN5,  MAX_DRILL_DEPTH = 93.35 MILS,  MFG_STUB_LENGTH = 0.00 MILS
;   BackdrillSize 1. = 17.700000 Tolerance = +0.000000/-0.000000 NON_PLATED MILS Quantity = 8
%
G90
X1592187Y-0082706
X1592187Y-0079306
X1582187Y-0040386
X1582187Y-0043786
X1801761Y-0040488
X1736405Y-0082678
X1736405Y-0079278
X1801761Y-0043888
M30
